(kicad_pcb
	(version 20221018)
	(generator pcbnew)
	(general
    (thickness 1.62)
  )
	(paper "A4")
	(title_block
    (title "ECP5 - Datacenter Secure Control Module (DC-SCM)")
    (date "2024-07-01")
    (rev "1.2.1")
		(comment 9 "footprints 172-178 of 506")
	)
	(layers
    (0 "F.Cu" signal)
    (1 "In1.Cu" power)
    (2 "In2.Cu" signal)
    (3 "In3.Cu" power)
    (4 "In4.Cu" power)
    (5 "In5.Cu" signal)
    (6 "In6.Cu" power)
    (31 "B.Cu" signal)
    (32 "B.Adhes" user "B.Adhesive")
    (33 "F.Adhes" user "F.Adhesive")
    (34 "B.Paste" user)
    (35 "F.Paste" user)
    (36 "B.SilkS" user "B.Silkscreen")
    (37 "F.SilkS" user "F.Silkscreen")
    (38 "B.Mask" user)
    (39 "F.Mask" user)
    (40 "Dwgs.User" user "User.Drawings")
    (41 "Cmts.User" user "User.Comments")
    (42 "Eco1.User" user "User.Eco1")
    (43 "Eco2.User" user "User.Eco2")
    (44 "Edge.Cuts" user)
    (45 "Margin" user)
    (46 "B.CrtYd" user "B.Courtyard")
    (47 "F.CrtYd" user "F.Courtyard")
    (48 "B.Fab" user)
    (49 "F.Fab" user)
  )
	(footprint "antmicro-footprints:L_WE-PDF-1064" (layer "F.Cu")
    (at 70.75 69.5 -90)
    (property "Author" "Antmicro")
    (property "IMax" "7.9 A")
    (property "ISat" "6 A")
    (property "License" "Apache-2.0")
    (property "MPN" "7447798720")
    (property "Manufacturer" "Würth Elektronik")
    (property "Public" "False")
    (property "Sheetfile" "power-supply.kicad_sch")
    (property "Sheetname" "Power supply")
    (property "Size" "10.2x10.2")
    (property "Val" "7u2/7.9A")
    (property "ki_description" "Power Inductor (SMD), 7.2 µH, 7.9 A, Shielded, 6 A, WE-PDF")
    (property "ki_keywords" "INDUCTOR, PASSIVE, SMT")
    (attr smd)
    (fp_text reference "L2" (at -5.745 4.38) (layer "F.SilkS")
        (effects (font (size 0.7 0.7) (thickness 0.127)))
    )
    (fp_text value "WE_7447798720" (at 0 0) (layer "F.SilkS") hide
        (effects (font (size 1.524 1.524) (thickness 0.05)))
    )
    (fp_text user "WE_7447798720" (at 0 0) (layer "F.SilkS") hide
        (effects (font (size 1.524 1.524) (thickness 0.05)))
    )
    (fp_text user "${REFERENCE}" (at -5.6 11 -90) (layer "F.Fab") hide
        (effects (font (size 0.7 0.7) (thickness 0.15)) (justify left bottom))
    )
    (fp_text user "Author: Antmicro" (at -5.6 9.8 -90) (layer "F.Fab") hide
        (effects (font (size 0.7 0.7) (thickness 0.15)) (justify left bottom))
    )
    (fp_text user "License: Apache-2.0" (at -5.6 8.6 -90) (layer "F.Fab") hide
        (effects (font (size 0.7 0.7) (thickness 0.15)) (justify left bottom))
    )
    (fp_line (start -5.225 -5.225) (end 4.125 -5.225)
      (stroke (width 0.15) (type solid)) (layer "F.SilkS"))
    (fp_line (start -5.225 -1.925) (end -5.225 -5.225)
      (stroke (width 0.15) (type solid)) (layer "F.SilkS"))
    (fp_line (start -5.225 5.225) (end -5.225 1.925)
      (stroke (width 0.15) (type solid)) (layer "F.SilkS"))
    (fp_line (start 4.125 -5.225) (end 5.225 -4.125)
      (stroke (width 0.15) (type solid)) (layer "F.SilkS"))
    (fp_line (start 5.225 -4.125) (end 5.225 -1.925)
      (stroke (width 0.15) (type solid)) (layer "F.SilkS"))
    (fp_line (start 5.225 1.925) (end 5.225 5.225)
      (stroke (width 0.15) (type solid)) (layer "F.SilkS"))
    (fp_line (start 5.225 5.225) (end -5.225 5.225)
      (stroke (width 0.15) (type solid)) (layer "F.SilkS"))
    (fp_line (start -5.55 -1.95) (end -5.55 1.95)
      (stroke (width 0.05) (type solid)) (layer "F.CrtYd"))
    (fp_line (start -5.55 1.95) (end -5.35 1.95)
      (stroke (width 0.05) (type solid)) (layer "F.CrtYd"))
    (fp_line (start -5.35 -5.35) (end -5.35 -1.95)
      (stroke (width 0.05) (type solid)) (layer "F.CrtYd"))
    (fp_line (start -5.35 -1.95) (end -5.55 -1.95)
      (stroke (width 0.05) (type solid)) (layer "F.CrtYd"))
    (fp_line (start -5.35 1.95) (end -5.35 5.35)
      (stroke (width 0.05) (type solid)) (layer "F.CrtYd"))
    (fp_line (start -5.35 5.35) (end 5.35 5.35)
      (stroke (width 0.05) (type solid)) (layer "F.CrtYd"))
    (fp_line (start 5.35 -5.35) (end -5.35 -5.35)
      (stroke (width 0.05) (type solid)) (layer "F.CrtYd"))
    (fp_line (start 5.35 -1.95) (end 5.35 -5.35)
      (stroke (width 0.05) (type solid)) (layer "F.CrtYd"))
    (fp_line (start 5.35 1.95) (end 5.55 1.95)
      (stroke (width 0.05) (type solid)) (layer "F.CrtYd"))
    (fp_line (start 5.35 5.35) (end 5.35 1.95)
      (stroke (width 0.05) (type solid)) (layer "F.CrtYd"))
    (fp_line (start 5.55 -1.95) (end 5.35 -1.95)
      (stroke (width 0.05) (type solid)) (layer "F.CrtYd"))
    (fp_line (start 5.55 -1.95) (end 5.55 1.95)
      (stroke (width 0.05) (type solid)) (layer "F.CrtYd"))
    (fp_rect (start -5.101 -5.101) (end 5.099 5.099)
      (stroke (width 0.15) (type solid)) (fill none) (layer "F.Fab"))
    (pad "1" smd roundrect (at -4.1 0) (size 3.4 2.4) (layers "F.Cu" "F.Paste" "F.Mask") (roundrect_rratio 0.1)
      (net 265 "Net-(D6-C)") (pintype "passive"))
    (pad "2" smd roundrect (at 4.1 0) (size 3.4 2.4) (layers "F.Cu" "F.Paste" "F.Mask") (roundrect_rratio 0.1)
      (net 290 "Net-(C110-Pad2)") (pintype "passive"))
  )
	(footprint "antmicro-footprints:C_0402_1005Metric" (layer "F.Cu")
    (at 120.539056 82.593104)
    (descr "Capacitor SMD 0402")
    (tags "capacitor SMD 0402")
    (property "Author" "Antmicro")
    (property "Dielectric" "")
    (property "License" "Apache-2.0")
    (property "MPN" "CC0402MRX5R5BB106")
    (property "Manufacturer" "YAGEO")
    (property "Public" "False")
    (property "Sheetfile" "power-supply.kicad_sch")
    (property "Sheetname" "Power supply")
    (property "Val" "10u")
    (property "Voltage" "")
    (property "ki_description" "SMD Multilayer Ceramic Capacitor, 10 µF, 6.3 V, 0402 [1005 Metric], ± 20%, X5R, CC Series")
    (property "ki_keywords" "0402, SMT, CAPACITOR, PASSIVE, MLCC, CERAMIC")
    (attr smd)
    (fp_text reference "C129" (at 2.300944 -0.008104) (layer "F.SilkS")
        (effects (font (size 0.7 0.7) (thickness 0.127)))
    )
    (fp_text value "C_10u_0402" (at 0 1.17) (layer "F.Fab")
        (effects (font (size 1 1) (thickness 0.15)))
    )
    (fp_text user "License: Apache-2.0" (at -0.939 5.799) (layer "F.Fab") hide
        (effects (font (size 0.7 0.7) (thickness 0.15)) (justify left bottom))
    )
    (fp_text user "Author: Antmicro" (at -0.939 3.399) (layer "F.Fab") hide
        (effects (font (size 0.7 0.7) (thickness 0.15)) (justify left bottom))
    )
    (fp_text user "${REFERENCE}" (at 0 0) (layer "F.Fab")
        (effects (font (size 0.25 0.25) (thickness 0.04)))
    )
    (fp_rect (start -0.925 -0.47) (end 0.925 0.47)
      (stroke (width 0.05) (type default)) (fill none) (layer "F.CrtYd"))
    (fp_line (start -0.494 -0.25) (end 0.504 -0.25)
      (stroke (width 0.15) (type solid)) (layer "F.Fab"))
    (fp_line (start -0.494 0.248) (end -0.494 -0.25)
      (stroke (width 0.15) (type solid)) (layer "F.Fab"))
    (fp_line (start 0.504 -0.25) (end 0.504 0.248)
      (stroke (width 0.15) (type solid)) (layer "F.Fab"))
    (fp_line (start 0.504 0.248) (end -0.494 0.248)
      (stroke (width 0.15) (type solid)) (layer "F.Fab"))
    (pad "1" smd roundrect (at -0.48 0) (size 0.59 0.64) (layers "F.Cu" "F.Paste" "F.Mask") (roundrect_rratio 0.25)
      (net 1 "GND") (pintype "passive"))
    (pad "2" smd roundrect (at 0.48 0) (size 0.59 0.64) (layers "F.Cu" "F.Paste" "F.Mask") (roundrect_rratio 0.25)
      (net 356 "Net-(C119-Pad2)") (pintype "passive"))
  )
	(footprint "antmicro-footprints:C_0603_1608Metric" (layer "F.Cu")
    (at 84.85 66.58 90)
    (descr "Capacitor SMD 0603")
    (tags "capacitor 0603")
    (property "Author" "Antmicro")
    (property "Dielectric" "")
    (property "License" "Apache-2.0")
    (property "MPN" "C1608X5R1E106M080AC")
    (property "Manufacturer" "TDK")
    (property "Public" "False")
    (property "Sheetfile" "power-supply.kicad_sch")
    (property "Sheetname" "Power supply")
    (property "Val" "10u")
    (property "Voltage" "25V")
    (property "ki_description" "SMD Multilayer Ceramic Capacitor, 10 µF, 25 V, 0603 [1608 Metric], ± 20%, X5R, C")
    (property "ki_keywords" "0603, SMT, CAPACITOR, PASSIVE, CERAMIC, MLCC")
    (attr smd)
    (fp_text reference "C101" (at -2.555 0.14 90) (layer "F.SilkS")
        (effects (font (size 0.7 0.7) (thickness 0.127)))
    )
    (fp_text value "C_10u_25V_0603" (at 0 1.9 90) (layer "F.Fab")
        (effects (font (size 1 1) (thickness 0.15)))
    )
    (fp_text user "License: Apache-2.0" (at -1.682 5.895 90) (layer "F.Fab") hide
        (effects (font (size 0.7 0.7) (thickness 0.15)) (justify left bottom))
    )
    (fp_text user "${REFERENCE}" (at -1.682 3.895 90) (layer "F.Fab") hide
        (effects (font (size 0.7 0.7) (thickness 0.15)) (justify left bottom))
    )
    (fp_text user "Author: Antmicro" (at -1.682 4.894 90) (layer "F.Fab") hide
        (effects (font (size 0.7 0.7) (thickness 0.15)) (justify left bottom))
    )
    (fp_line (start -0.15 -0.4) (end 0.15 -0.4)
      (stroke (width 0.15) (type solid)) (layer "F.SilkS"))
    (fp_line (start -0.15 0.4) (end 0.15 0.4)
      (stroke (width 0.15) (type solid)) (layer "F.SilkS"))
    (fp_rect (start -1.25 -0.65) (end 1.25 0.65)
      (stroke (width 0.05) (type solid)) (fill none) (layer "F.CrtYd"))
    (fp_rect (start -0.8 -0.4) (end 0.8 0.4)
      (stroke (width 0.15) (type solid)) (fill none) (layer "F.Fab"))
    (pad "1" smd roundrect (at -0.7 0 90) (size 0.8 1) (layers "F.Cu" "F.Paste" "F.Mask") (roundrect_rratio 0.2)
      (net 1 "GND") (pintype "passive"))
    (pad "2" smd roundrect (at 0.7 0 90) (size 0.8 1) (layers "F.Cu" "F.Paste" "F.Mask") (roundrect_rratio 0.2)
      (net 15 "VCC12V") (pintype "passive"))
  )
	(footprint "antmicro-footprints:C_0603_1608Metric" (layer "F.Cu")
    (at 83.35 66.58 90)
    (descr "Capacitor SMD 0603")
    (tags "capacitor 0603")
    (property "Author" "Antmicro")
    (property "Dielectric" "")
    (property "License" "Apache-2.0")
    (property "MPN" "C1608X5R1E106M080AC")
    (property "Manufacturer" "TDK")
    (property "Public" "False")
    (property "Sheetfile" "power-supply.kicad_sch")
    (property "Sheetname" "Power supply")
    (property "Val" "10u")
    (property "Voltage" "25V")
    (property "ki_description" "SMD Multilayer Ceramic Capacitor, 10 µF, 25 V, 0603 [1608 Metric], ± 20%, X5R, C")
    (property "ki_keywords" "0603, SMT, CAPACITOR, PASSIVE, CERAMIC, MLCC")
    (attr smd)
    (fp_text reference "C260" (at -2.485 -0.72 90) (layer "F.SilkS")
        (effects (font (size 0.7 0.7) (thickness 0.127)))
    )
    (fp_text value "C_10u_25V_0603" (at 0 1.9 90) (layer "F.Fab")
        (effects (font (size 1 1) (thickness 0.15)))
    )
    (fp_text user "Author: Antmicro" (at -1.682 4.894 90) (layer "F.Fab") hide
        (effects (font (size 0.7 0.7) (thickness 0.15)) (justify left bottom))
    )
    (fp_text user "${REFERENCE}" (at -1.682 3.895 90) (layer "F.Fab") hide
        (effects (font (size 0.7 0.7) (thickness 0.15)) (justify left bottom))
    )
    (fp_text user "License: Apache-2.0" (at -1.682 5.895 90) (layer "F.Fab") hide
        (effects (font (size 0.7 0.7) (thickness 0.15)) (justify left bottom))
    )
    (fp_line (start -0.15 -0.4) (end 0.15 -0.4)
      (stroke (width 0.15) (type solid)) (layer "F.SilkS"))
    (fp_line (start -0.15 0.4) (end 0.15 0.4)
      (stroke (width 0.15) (type solid)) (layer "F.SilkS"))
    (fp_rect (start -1.25 -0.65) (end 1.25 0.65)
      (stroke (width 0.05) (type solid)) (fill none) (layer "F.CrtYd"))
    (fp_rect (start -0.8 -0.4) (end 0.8 0.4)
      (stroke (width 0.15) (type solid)) (fill none) (layer "F.Fab"))
    (pad "1" smd roundrect (at -0.7 0 90) (size 0.8 1) (layers "F.Cu" "F.Paste" "F.Mask") (roundrect_rratio 0.2)
      (net 1 "GND") (pintype "passive"))
    (pad "2" smd roundrect (at 0.7 0 90) (size 0.8 1) (layers "F.Cu" "F.Paste" "F.Mask") (roundrect_rratio 0.2)
      (net 15 "VCC12V") (pintype "passive"))
  )
	(footprint "antmicro-footprints:C_0603_1608Metric" (layer "F.Cu")
    (at 86.35 66.58 90)
    (descr "Capacitor SMD 0603")
    (tags "capacitor 0603")
    (property "Author" "Antmicro")
    (property "Dielectric" "")
    (property "License" "Apache-2.0")
    (property "MPN" "C1608X5R1E106M080AC")
    (property "Manufacturer" "TDK")
    (property "Public" "False")
    (property "Sheetfile" "power-supply.kicad_sch")
    (property "Sheetname" "Power supply")
    (property "Val" "10u")
    (property "Voltage" "25V")
    (property "ki_description" "SMD Multilayer Ceramic Capacitor, 10 µF, 25 V, 0603 [1608 Metric], ± 20%, X5R, C")
    (property "ki_keywords" "0603, SMT, CAPACITOR, PASSIVE, CERAMIC, MLCC")
    (attr smd)
    (fp_text reference "C261" (at -2.465 0.7 90) (layer "F.SilkS")
        (effects (font (size 0.7 0.7) (thickness 0.127)))
    )
    (fp_text value "C_10u_25V_0603" (at 0 1.9 90) (layer "F.Fab")
        (effects (font (size 1 1) (thickness 0.15)))
    )
    (fp_text user "Author: Antmicro" (at -1.682 4.894 90) (layer "F.Fab") hide
        (effects (font (size 0.7 0.7) (thickness 0.15)) (justify left bottom))
    )
    (fp_text user "${REFERENCE}" (at -1.682 3.895 90) (layer "F.Fab") hide
        (effects (font (size 0.7 0.7) (thickness 0.15)) (justify left bottom))
    )
    (fp_text user "License: Apache-2.0" (at -1.682 5.895 90) (layer "F.Fab") hide
        (effects (font (size 0.7 0.7) (thickness 0.15)) (justify left bottom))
    )
    (fp_line (start -0.15 -0.4) (end 0.15 -0.4)
      (stroke (width 0.15) (type solid)) (layer "F.SilkS"))
    (fp_line (start -0.15 0.4) (end 0.15 0.4)
      (stroke (width 0.15) (type solid)) (layer "F.SilkS"))
    (fp_rect (start -1.25 -0.65) (end 1.25 0.65)
      (stroke (width 0.05) (type solid)) (fill none) (layer "F.CrtYd"))
    (fp_rect (start -0.8 -0.4) (end 0.8 0.4)
      (stroke (width 0.15) (type solid)) (fill none) (layer "F.Fab"))
    (pad "1" smd roundrect (at -0.7 0 90) (size 0.8 1) (layers "F.Cu" "F.Paste" "F.Mask") (roundrect_rratio 0.2)
      (net 1 "GND") (pintype "passive"))
    (pad "2" smd roundrect (at 0.7 0 90) (size 0.8 1) (layers "F.Cu" "F.Paste" "F.Mask") (roundrect_rratio 0.2)
      (net 15 "VCC12V") (pintype "passive"))
  )
	(footprint "antmicro-footprints:C_0402_1005Metric" (layer "F.Cu")
    (at 81.89 63.9 -90)
    (descr "Capacitor SMD 0402")
    (tags "capacitor SMD 0402")
    (property "Author" "Antmicro")
    (property "Dielectric" "X7R")
    (property "License" "Apache-2.0")
    (property "MPN" "GRM155R71H103KA88D")
    (property "Manufacturer" "Murata")
    (property "Public" "False")
    (property "Sheetfile" "power-supply.kicad_sch")
    (property "Sheetname" "Power supply")
    (property "Val" "10n")
    (property "Voltage" "50V")
    (property "ki_description" "SMD Multilayer Ceramic Capacitor, 10000 pF, 50 V, 0402 [1005 Metric], ± 10%, X7R, GRM Series")
    (property "ki_keywords" "0402, SMT, CAPACITOR, PASSIVE")
    (attr smd)
    (fp_text reference "C59" (at -1.85 -0.04 90) (layer "F.SilkS")
        (effects (font (size 0.7 0.7) (thickness 0.127)))
    )
    (fp_text value "C_10n_0402" (at 0 1.17 90) (layer "F.Fab")
        (effects (font (size 1 1) (thickness 0.15)))
    )
    (fp_text user "${REFERENCE}" (at 0 0 90) (layer "F.Fab")
        (effects (font (size 0.25 0.25) (thickness 0.04)))
    )
    (fp_text user "Author: Antmicro" (at -0.939 3.399 90) (layer "F.Fab") hide
        (effects (font (size 0.7 0.7) (thickness 0.15)) (justify right bottom))
    )
    (fp_text user "License: Apache-2.0" (at -0.939 5.799 90) (layer "F.Fab") hide
        (effects (font (size 0.7 0.7) (thickness 0.15)) (justify right bottom))
    )
    (fp_rect (start -0.925 -0.47) (end 0.925 0.47)
      (stroke (width 0.05) (type default)) (fill none) (layer "F.CrtYd"))
    (fp_line (start -0.494 -0.25) (end 0.504 -0.25)
      (stroke (width 0.15) (type solid)) (layer "F.Fab"))
    (fp_line (start -0.494 0.248) (end -0.494 -0.25)
      (stroke (width 0.15) (type solid)) (layer "F.Fab"))
    (fp_line (start 0.504 -0.25) (end 0.504 0.248)
      (stroke (width 0.15) (type solid)) (layer "F.Fab"))
    (fp_line (start 0.504 0.248) (end -0.494 0.248)
      (stroke (width 0.15) (type solid)) (layer "F.Fab"))
    (pad "1" smd roundrect (at -0.48 0 270) (size 0.59 0.64) (layers "F.Cu" "F.Paste" "F.Mask") (roundrect_rratio 0.25)
      (net 1 "GND") (pintype "passive"))
    (pad "2" smd roundrect (at 0.48 0 270) (size 0.59 0.64) (layers "F.Cu" "F.Paste" "F.Mask") (roundrect_rratio 0.25)
      (net 780 "Net-(U15-SS{slash}TR)") (pintype "passive"))
  )
	(footprint "antmicro-footprints:C_0603_1608Metric" (layer "F.Cu")
    (at 79.9 68.65 -90)
    (descr "Capacitor SMD 0603")
    (tags "capacitor 0603")
    (property "Author" "Antmicro")
    (property "Dielectric" "")
    (property "License" "Apache-2.0")
    (property "MPN" "GRM188R60J476ME15D")
    (property "Manufacturer" "Murata")
    (property "Public" "False")
    (property "Sheetfile" "power-supply.kicad_sch")
    (property "Sheetname" "Power supply")
    (property "Val" "47u")
    (property "Voltage" "")
    (property "ki_description" "SMD Multilayer Ceramic Capacitor, 47 µF, 6.3 V, 0603 [1608 Metric], ± 20%, X5R, GRM Series")
    (property "ki_keywords" "0603, SMT, CAPACITOR, PASSIVE, CERAMIC, MLCC")
    (attr smd)
    (fp_text reference "C112" (at 0.505 -1.05 90) (layer "F.SilkS")
        (effects (font (size 0.7 0.7) (thickness 0.127)))
    )
    (fp_text value "C_47u_0603" (at 0 1.9 90) (layer "F.Fab")
        (effects (font (size 1 1) (thickness 0.15)))
    )
    (fp_text user "${REFERENCE}" (at -1.682 3.895 -90) (layer "F.Fab") hide
        (effects (font (size 0.7 0.7) (thickness 0.15)) (justify left bottom))
    )
    (fp_text user "Author: Antmicro" (at -1.682 4.894 -90) (layer "F.Fab") hide
        (effects (font (size 0.7 0.7) (thickness 0.15)) (justify left bottom))
    )
    (fp_text user "License: Apache-2.0" (at -1.682 5.895 -90) (layer "F.Fab") hide
        (effects (font (size 0.7 0.7) (thickness 0.15)) (justify left bottom))
    )
    (fp_line (start -0.15 -0.4) (end 0.15 -0.4)
      (stroke (width 0.15) (type solid)) (layer "F.SilkS"))
    (fp_line (start -0.15 0.4) (end 0.15 0.4)
      (stroke (width 0.15) (type solid)) (layer "F.SilkS"))
    (fp_rect (start -1.25 -0.65) (end 1.25 0.65)
      (stroke (width 0.05) (type solid)) (fill none) (layer "F.CrtYd"))
    (fp_rect (start -0.8 -0.4) (end 0.8 0.4)
      (stroke (width 0.15) (type solid)) (fill none) (layer "F.Fab"))
    (pad "1" smd roundrect (at -0.7 0 270) (size 0.8 1) (layers "F.Cu" "F.Paste" "F.Mask") (roundrect_rratio 0.2)
      (net 1 "GND") (pintype "passive"))
    (pad "2" smd roundrect (at 0.7 0 270) (size 0.8 1) (layers "F.Cu" "F.Paste" "F.Mask") (roundrect_rratio 0.2)
      (net 290 "Net-(C110-Pad2)") (pintype "passive"))
  )
)
